FILE_TYPE = MULTI_PHYS_TABLE;

PART 'POWERMOS_3P_NCH_V1'
CLASS=DISCRETE

{========================================================================================}
:CLS_PN             = JEDEC_TYPE      | ALT_SYMBOLS       | DESCRIPTION                                              | CPN_STATUS ;
{========================================================================================}
 'G121-00015-01'    = 'SOT23_V1'      | '(SOT23_V1)'      | 'FET,2N7002,60V,N-CH,7.5OHM,SOT23'                       | ''        
 'G121-10134-01'    = 'SOT23_V1_H044' | '(SOT23_V1_H044)' | 'FET,N-CH,MGSF1N02L,20V,0.09OHM,750MA,SOT-23'            | ''        
 'G121-00032-01'    = 'SOT23_V1'      | '(SOT23_V1)'      | 'FET,BSS138,50V,N-CH,6OHM,SOT23'                         | ''        
 'G121-10047-01'    = 'SOT23_V1'      | '(SOT23_V1)'      | 'FET,MOSFET,N-CH,20V,0.085OHM,3.2A,SOT-23'               | ''        
 'G121-10163-01'    = 'TO263_V2'      | '(TO263_V2)'      | 'FET,N-CH,DEPLETION MODE,IXTA1N170DHV,1A,1700V,TO-263HV' | ''        
 'G121-10166-01'    = 'SOT23_V1_H047' | '(SOT23_V1_H047)' | 'FET,N-CH,ZXMN10A07F,100V,0.54OHM,0.7A,SOT-23'           | ''        
 'G121-10171-01'    = 'SOT23_V1_H044' | '(SOT23_V1_H044)' | 'FET,N-CH,100V,6 OHM,170MA,SOT-23-3'                     | ''        
 'G121-10185-01'    = 'SOT23_V1_H039' | '(SOT23_V1_H039)' | 'FET,N-CH,BSS214NW,20V,0.140/0.250 OHM,PG-SOT323'        | ''        
 'G121-10200-01'    = 'SOT23_V1_H044' | '(SOT23_V1_H044)' | 'FET,N-CH,50V,3.5OHM,200MA,SOT23'                        | ''        

END_PART

END.

